(kicad_pcb
	(version 20260206)
	(generator "pcbnew")
	(generator_version "10.0")
	(general
		(thickness 1.6)
		(legacy_teardrops no)
	)
	(paper "A4")
	(title_block
		(title "04192023_DAF0TMB3IC0_F0TG_MB_C_brd_V02_OCP.brd")
		(comment 1 "Grand Teton / footprints 365-372 of 8354")
	)
	(layers
		(0 "F.Cu" signal "TOP")
		(4 "In1.Cu" signal "GND")
		(6 "In2.Cu" signal "IN1")
		(8 "In3.Cu" signal "GND1")
		(10 "In4.Cu" signal "IN2")
		(12 "In5.Cu" signal "GND2")
		(14 "In6.Cu" signal "IN3")
		(16 "In7.Cu" signal "GND3")
		(18 "In8.Cu" signal "VCC")
		(20 "In9.Cu" signal "VCC1")
		(22 "In10.Cu" signal "GND4")
		(24 "In11.Cu" signal "IN4")
		(26 "In12.Cu" signal "GND5")
		(28 "In13.Cu" signal "IN5")
		(30 "In14.Cu" signal "GND6")
		(32 "In15.Cu" signal "IN6")
		(34 "In16.Cu" signal "GND7")
		(2 "B.Cu" signal "BOTTOM")
		(9 "F.Adhes" user "F.Adhesive")
		(11 "B.Adhes" user "B.Adhesive")
		(13 "F.Paste" user "Package Geometry/Pastemask Top")
		(15 "B.Paste" user "Package Geometry/Pastemask Bottom")
		(5 "F.SilkS" user "Ref Des/Silkscreen Top")
		(7 "B.SilkS" user "Ref Des/Silkscreen Bottom")
		(1 "F.Mask" user "Board Geometry/Soldermask Top")
		(3 "B.Mask" user "Board Geometry/Soldermask Bottom")
		(17 "Dwgs.User" user "User.Drawings")
		(19 "Cmts.User" user "User.Comments")
		(21 "Eco1.User" user "User.Eco1")
		(23 "Eco2.User" user "User.Eco2")
		(25 "Edge.Cuts" user "Board Geometry/Outline")
		(27 "Margin" user)
		(31 "F.CrtYd" user "Package Geometry/Place Bound Top")
		(29 "B.CrtYd" user "Package Geometry/Place Bound Bottom")
		(35 "F.Fab" user "Ref Des/Assembly Top")
		(33 "B.Fab" user "Ref Des/Assembly Bottom")
	)
	(footprint ""
		(layer "F.Cu")
		(at 365.618522 -172.559726)
		(property "Reference" "PR320"
			(at 0 0 0)
			(layer "F.SilkS")
			(hide yes)
			(effects
				(font
					(size 1.27 1.27)
				)
			)
		)
		(property "Value" ""
			(at 0 0 0)
			(layer "F.Fab")
			(effects
				(font
					(size 1.27 1.27)
				)
			)
		)
		(duplicate_pad_numbers_are_jumpers no)
		(fp_line
			(start -0.7874 -0.4064)
			(end 0.7874 -0.4064)
			(stroke
				(width 0.1524)
				(type default)
			)
			(layer "F.SilkS")
		)
		(fp_line
			(start -0.7874 0.4064)
			(end -0.7874 -0.4064)
			(stroke
				(width 0.1524)
				(type default)
			)
			(layer "F.SilkS")
		)
		(fp_line
			(start 0.7874 -0.4064)
			(end 0.7874 0.4064)
			(stroke
				(width 0.1524)
				(type default)
			)
			(layer "F.SilkS")
		)
		(fp_line
			(start 0.7874 0.4064)
			(end -0.7874 0.4064)
			(stroke
				(width 0.1524)
				(type default)
			)
			(layer "F.SilkS")
		)
		(fp_line
			(start -0.67945 -0.305054)
			(end -0.12065 -0.305054)
			(stroke
				(width 0.1)
				(type default)
			)
			(layer "F.Fab")
		)
		(fp_line
			(start -0.67945 0.3048)
			(end -0.67945 -0.305054)
			(stroke
				(width 0.1)
				(type default)
			)
			(layer "F.Fab")
		)
		(fp_line
			(start -0.12065 -0.305054)
			(end -0.12065 -0.2794)
			(stroke
				(width 0.1)
				(type default)
			)
			(layer "F.Fab")
		)
		(fp_line
			(start -0.12065 -0.2794)
			(end 0.12065 -0.2794)
			(stroke
				(width 0.1)
				(type default)
			)
			(layer "F.Fab")
		)
		(fp_line
			(start -0.12065 0.2794)
			(end -0.12065 0.3048)
			(stroke
				(width 0.1)
				(type default)
			)
			(layer "F.Fab")
		)
		(fp_line
			(start -0.12065 0.3048)
			(end -0.67945 0.3048)
			(stroke
				(width 0.1)
				(type default)
			)
			(layer "F.Fab")
		)
		(fp_line
			(start 0.120396 0.2794)
			(end -0.12065 0.2794)
			(stroke
				(width 0.1)
				(type default)
			)
			(layer "F.Fab")
		)
		(fp_line
			(start 0.120396 0.3048)
			(end 0.120396 0.2794)
			(stroke
				(width 0.1)
				(type default)
			)
			(layer "F.Fab")
		)
		(fp_line
			(start 0.12065 -0.3048)
			(end 0.67945 -0.3048)
			(stroke
				(width 0.1)
				(type default)
			)
			(layer "F.Fab")
		)
		(fp_line
			(start 0.12065 -0.2794)
			(end 0.12065 -0.3048)
			(stroke
				(width 0.1)
				(type default)
			)
			(layer "F.Fab")
		)
		(fp_line
			(start 0.67945 -0.3048)
			(end 0.67945 0.3048)
			(stroke
				(width 0.1)
				(type default)
			)
			(layer "F.Fab")
		)
		(fp_line
			(start 0.67945 0.3048)
			(end 0.120396 0.3048)
			(stroke
				(width 0.1)
				(type default)
			)
			(layer "F.Fab")
		)
		(pad "1" smd circle
			(at -0.40005 0)
			(size 0 0)
			(layers "F.Cu" "F.Mask" "F.Paste")
			(net "GND")
		)
		(pad "2" smd circle
			(at 0.40005 0)
			(size 0 0)
			(layers "F.Cu" "F.Mask" "F.Paste")
			(net "PVDDCR_CPU0_P0_LSET1")
		)
	)
	(footprint ""
		(layer "F.Cu")
		(at 404.158958 -321.002152 90)
		(property "Reference" "R448"
			(at 0 0 90)
			(layer "F.SilkS")
			(hide yes)
			(effects
				(font
					(size 1.27 1.27)
				)
			)
		)
		(property "Value" ""
			(at 0 0 90)
			(layer "F.Fab")
			(effects
				(font
					(size 1.27 1.27)
				)
			)
		)
		(duplicate_pad_numbers_are_jumpers no)
		(fp_line
			(start 0.7874 -0.4064)
			(end 0.7874 0.4064)
			(stroke
				(width 0.1524)
				(type default)
			)
			(layer "F.SilkS")
		)
		(fp_line
			(start -0.7874 -0.4064)
			(end 0.7874 -0.4064)
			(stroke
				(width 0.1524)
				(type default)
			)
			(layer "F.SilkS")
		)
		(fp_line
			(start 0.7874 0.4064)
			(end -0.7874 0.4064)
			(stroke
				(width 0.1524)
				(type default)
			)
			(layer "F.SilkS")
		)
		(fp_line
			(start -0.7874 0.4064)
			(end -0.7874 -0.4064)
			(stroke
				(width 0.1524)
				(type default)
			)
			(layer "F.SilkS")
		)
		(fp_line
			(start -0.12065 -0.305054)
			(end -0.12065 -0.2794)
			(stroke
				(width 0.1)
				(type default)
			)
			(layer "F.Fab")
		)
		(fp_line
			(start -0.67945 -0.305054)
			(end -0.12065 -0.305054)
			(stroke
				(width 0.1)
				(type default)
			)
			(layer "F.Fab")
		)
		(fp_line
			(start 0.67945 -0.3048)
			(end 0.67945 0.3048)
			(stroke
				(width 0.1)
				(type default)
			)
			(layer "F.Fab")
		)
		(fp_line
			(start 0.12065 -0.3048)
			(end 0.67945 -0.3048)
			(stroke
				(width 0.1)
				(type default)
			)
			(layer "F.Fab")
		)
		(fp_line
			(start 0.12065 -0.2794)
			(end 0.12065 -0.3048)
			(stroke
				(width 0.1)
				(type default)
			)
			(layer "F.Fab")
		)
		(fp_line
			(start -0.12065 -0.2794)
			(end 0.12065 -0.2794)
			(stroke
				(width 0.1)
				(type default)
			)
			(layer "F.Fab")
		)
		(fp_line
			(start 0.120396 0.2794)
			(end -0.12065 0.2794)
			(stroke
				(width 0.1)
				(type default)
			)
			(layer "F.Fab")
		)
		(fp_line
			(start -0.12065 0.2794)
			(end -0.12065 0.3048)
			(stroke
				(width 0.1)
				(type default)
			)
			(layer "F.Fab")
		)
		(fp_line
			(start 0.67945 0.3048)
			(end 0.120396 0.3048)
			(stroke
				(width 0.1)
				(type default)
			)
			(layer "F.Fab")
		)
		(fp_line
			(start 0.120396 0.3048)
			(end 0.120396 0.2794)
			(stroke
				(width 0.1)
				(type default)
			)
			(layer "F.Fab")
		)
		(fp_line
			(start -0.12065 0.3048)
			(end -0.67945 0.3048)
			(stroke
				(width 0.1)
				(type default)
			)
			(layer "F.Fab")
		)
		(fp_line
			(start -0.67945 0.3048)
			(end -0.67945 -0.305054)
			(stroke
				(width 0.1)
				(type default)
			)
			(layer "F.Fab")
		)
		(pad "1" smd circle
			(at -0.40005 0 90)
			(size 0 0)
			(layers "F.Cu" "F.Mask" "F.Paste")
			(net "CPU0_SLP_S5_N")
		)
		(pad "2" smd circle
			(at 0.40005 0 90)
			(size 0 0)
			(layers "F.Cu" "F.Mask" "F.Paste")
			(net "PVDD18_S5_P0")
		)
	)
	(footprint ""
		(layer "F.Cu")
		(at 180.528468 -45.005498)
		(property "Reference" "C9105"
			(at 0 0 0)
			(layer "F.SilkS")
			(hide yes)
			(effects
				(font
					(size 1.27 1.27)
				)
			)
		)
		(property "Value" ""
			(at 0 0 0)
			(layer "F.Fab")
			(effects
				(font
					(size 1.27 1.27)
				)
			)
		)
		(duplicate_pad_numbers_are_jumpers no)
		(fp_line
			(start -0.299974 -0.150114)
			(end 0.299974 -0.150114)
			(stroke
				(width 0.1)
				(type default)
			)
			(layer "F.Fab")
		)
		(fp_line
			(start -0.299974 0.150114)
			(end -0.299974 -0.150114)
			(stroke
				(width 0.1)
				(type default)
			)
			(layer "F.Fab")
		)
		(fp_line
			(start 0.299974 -0.150114)
			(end 0.299974 0.150114)
			(stroke
				(width 0.1)
				(type default)
			)
			(layer "F.Fab")
		)
		(fp_line
			(start 0.299974 0.150114)
			(end -0.299974 0.150114)
			(stroke
				(width 0.1)
				(type default)
			)
			(layer "F.Fab")
		)
		(pad "1" smd rect
			(at -0.2667 0)
			(size 0.3048 0.381)
			(layers "F.Cu" "F.Mask" "F.Paste")
			(net "P3E_CPU1_P4_TX_C_DN<0>")
		)
		(pad "2" smd rect
			(at 0.2667 0)
			(size 0.3048 0.381)
			(layers "F.Cu" "F.Mask" "F.Paste")
			(net "P3E_CPU1_P4_TX_DN<0>")
		)
	)
	(footprint ""
		(layer "F.Cu")
		(at 422.148 -55.753 90)
		(property "Reference" "R8019"
			(at 0 0 90)
			(layer "F.SilkS")
			(hide yes)
			(effects
				(font
					(size 1.27 1.27)
				)
			)
		)
		(property "Value" ""
			(at 0 0 90)
			(layer "F.Fab")
			(effects
				(font
					(size 1.27 1.27)
				)
			)
		)
		(duplicate_pad_numbers_are_jumpers no)
		(fp_line
			(start 0.7874 -0.4064)
			(end 0.7874 0.4064)
			(stroke
				(width 0.1524)
				(type default)
			)
			(layer "F.SilkS")
		)
		(fp_line
			(start -0.7874 -0.4064)
			(end 0.7874 -0.4064)
			(stroke
				(width 0.1524)
				(type default)
			)
			(layer "F.SilkS")
		)
		(fp_line
			(start 0.7874 0.4064)
			(end -0.7874 0.4064)
			(stroke
				(width 0.1524)
				(type default)
			)
			(layer "F.SilkS")
		)
		(fp_line
			(start -0.7874 0.4064)
			(end -0.7874 -0.4064)
			(stroke
				(width 0.1524)
				(type default)
			)
			(layer "F.SilkS")
		)
		(fp_line
			(start -0.12065 -0.305054)
			(end -0.12065 -0.2794)
			(stroke
				(width 0.1)
				(type default)
			)
			(layer "F.Fab")
		)
		(fp_line
			(start -0.67945 -0.305054)
			(end -0.12065 -0.305054)
			(stroke
				(width 0.1)
				(type default)
			)
			(layer "F.Fab")
		)
		(fp_line
			(start 0.67945 -0.3048)
			(end 0.67945 0.3048)
			(stroke
				(width 0.1)
				(type default)
			)
			(layer "F.Fab")
		)
		(fp_line
			(start 0.12065 -0.3048)
			(end 0.67945 -0.3048)
			(stroke
				(width 0.1)
				(type default)
			)
			(layer "F.Fab")
		)
		(fp_line
			(start 0.12065 -0.2794)
			(end 0.12065 -0.3048)
			(stroke
				(width 0.1)
				(type default)
			)
			(layer "F.Fab")
		)
		(fp_line
			(start -0.12065 -0.2794)
			(end 0.12065 -0.2794)
			(stroke
				(width 0.1)
				(type default)
			)
			(layer "F.Fab")
		)
		(fp_line
			(start 0.120396 0.2794)
			(end -0.12065 0.2794)
			(stroke
				(width 0.1)
				(type default)
			)
			(layer "F.Fab")
		)
		(fp_line
			(start -0.12065 0.2794)
			(end -0.12065 0.3048)
			(stroke
				(width 0.1)
				(type default)
			)
			(layer "F.Fab")
		)
		(fp_line
			(start 0.67945 0.3048)
			(end 0.120396 0.3048)
			(stroke
				(width 0.1)
				(type default)
			)
			(layer "F.Fab")
		)
		(fp_line
			(start 0.120396 0.3048)
			(end 0.120396 0.2794)
			(stroke
				(width 0.1)
				(type default)
			)
			(layer "F.Fab")
		)
		(fp_line
			(start -0.12065 0.3048)
			(end -0.67945 0.3048)
			(stroke
				(width 0.1)
				(type default)
			)
			(layer "F.Fab")
		)
		(fp_line
			(start -0.67945 0.3048)
			(end -0.67945 -0.305054)
			(stroke
				(width 0.1)
				(type default)
			)
			(layer "F.Fab")
		)
		(pad "1" smd circle
			(at -0.40005 0 90)
			(size 0 0)
			(layers "F.Cu" "F.Mask" "F.Paste")
			(net "P3V3_AUX")
		)
		(pad "2" smd circle
			(at 0.40005 0 90)
			(size 0 0)
			(layers "F.Cu" "F.Mask" "F.Paste")
			(net "FM_JTAG_BMC_R_OE")
		)
	)
	(footprint ""
		(layer "F.Cu")
		(at 102.362 -77.216 180)
		(property "Reference" "R1167"
			(at 0 0 180)
			(layer "F.SilkS")
			(hide yes)
			(effects
				(font
					(size 1.27 1.27)
				)
			)
		)
		(property "Value" ""
			(at 0 0 180)
			(layer "F.Fab")
			(effects
				(font
					(size 1.27 1.27)
				)
			)
		)
		(duplicate_pad_numbers_are_jumpers no)
		(fp_line
			(start 0.7874 0.4064)
			(end -0.7874 0.4064)
			(stroke
				(width 0.1524)
				(type default)
			)
			(layer "F.SilkS")
		)
		(fp_line
			(start 0.7874 -0.4064)
			(end 0.7874 0.4064)
			(stroke
				(width 0.1524)
				(type default)
			)
			(layer "F.SilkS")
		)
		(fp_line
			(start -0.7874 0.4064)
			(end -0.7874 -0.4064)
			(stroke
				(width 0.1524)
				(type default)
			)
			(layer "F.SilkS")
		)
		(fp_line
			(start -0.7874 -0.4064)
			(end 0.7874 -0.4064)
			(stroke
				(width 0.1524)
				(type default)
			)
			(layer "F.SilkS")
		)
		(fp_line
			(start 0.67945 0.3048)
			(end 0.120396 0.3048)
			(stroke
				(width 0.1)
				(type default)
			)
			(layer "F.Fab")
		)
		(fp_line
			(start 0.67945 -0.3048)
			(end 0.67945 0.3048)
			(stroke
				(width 0.1)
				(type default)
			)
			(layer "F.Fab")
		)
		(fp_line
			(start 0.12065 -0.2794)
			(end 0.12065 -0.3048)
			(stroke
				(width 0.1)
				(type default)
			)
			(layer "F.Fab")
		)
		(fp_line
			(start 0.12065 -0.3048)
			(end 0.67945 -0.3048)
			(stroke
				(width 0.1)
				(type default)
			)
			(layer "F.Fab")
		)
		(fp_line
			(start 0.120396 0.3048)
			(end 0.120396 0.2794)
			(stroke
				(width 0.1)
				(type default)
			)
			(layer "F.Fab")
		)
		(fp_line
			(start 0.120396 0.2794)
			(end -0.12065 0.2794)
			(stroke
				(width 0.1)
				(type default)
			)
			(layer "F.Fab")
		)
		(fp_line
			(start -0.12065 0.3048)
			(end -0.67945 0.3048)
			(stroke
				(width 0.1)
				(type default)
			)
			(layer "F.Fab")
		)
		(fp_line
			(start -0.12065 0.2794)
			(end -0.12065 0.3048)
			(stroke
				(width 0.1)
				(type default)
			)
			(layer "F.Fab")
		)
		(fp_line
			(start -0.12065 -0.2794)
			(end 0.12065 -0.2794)
			(stroke
				(width 0.1)
				(type default)
			)
			(layer "F.Fab")
		)
		(fp_line
			(start -0.12065 -0.305054)
			(end -0.12065 -0.2794)
			(stroke
				(width 0.1)
				(type default)
			)
			(layer "F.Fab")
		)
		(fp_line
			(start -0.67945 0.3048)
			(end -0.67945 -0.305054)
			(stroke
				(width 0.1)
				(type default)
			)
			(layer "F.Fab")
		)
		(fp_line
			(start -0.67945 -0.305054)
			(end -0.12065 -0.305054)
			(stroke
				(width 0.1)
				(type default)
			)
			(layer "F.Fab")
		)
		(pad "1" smd circle
			(at -0.40005 0 180)
			(size 0 0)
			(layers "F.Cu" "F.Mask" "F.Paste")
			(net "P3V3_AUX")
		)
		(pad "2" smd circle
			(at 0.40005 0 180)
			(size 0 0)
			(layers "F.Cu" "F.Mask" "F.Paste")
			(net "P12V_OCP_V3_2_PLD_PWRGD")
		)
	)
	(footprint ""
		(layer "F.Cu")
		(at 267.45184 -347.8149)
		(property "Reference" "H50"
			(at -1.7526 -4.34213 0)
			(unlocked yes)
			(layer "F.SilkS")
			(effects
				(font
					(size 0.7874 0.5842)
					(thickness 0.1524)
				)
				(justify left)
			)
		)
		(property "Value" ""
			(at 0 0 0)
			(layer "F.Fab")
			(effects
				(font
					(size 1.27 1.27)
				)
			)
		)
		(duplicate_pad_numbers_are_jumpers no)
		(pad "1" thru_hole circle
			(at 0 0)
			(size 6.1976 6.1976)
			(drill 3.7338)
			(layers "*.Cu" "*.Mask")
			(remove_unused_layers no)
			(net "GND")
			(clearance -0.9779)
			(padstack
				(mode front_inner_back)
				(layer "Inner"
					(shape circle)
					(size 5.5372 5.5372)
					(clearance -0.6477)
				)
				(layer "B.Cu"
					(shape circle)
					(size 6.1976 6.1976)
					(clearance -0.9779)
				)
			)
		)
	)
	(footprint ""
		(layer "F.Cu")
		(at 271.739106 -349.381572 90)
		(property "Reference" "PC171"
			(at 0 0 90)
			(layer "F.SilkS")
			(hide yes)
			(effects
				(font
					(size 1.27 1.27)
				)
			)
		)
		(property "Value" ""
			(at 0 0 90)
			(layer "F.Fab")
			(effects
				(font
					(size 1.27 1.27)
				)
			)
		)
		(duplicate_pad_numbers_are_jumpers no)
		(fp_line
			(start 0.7874 -0.4064)
			(end 0.7874 0.4064)
			(stroke
				(width 0.1524)
				(type default)
			)
			(layer "F.SilkS")
		)
		(fp_line
			(start -0.7874 -0.4064)
			(end 0.7874 -0.4064)
			(stroke
				(width 0.1524)
				(type default)
			)
			(layer "F.SilkS")
		)
		(fp_line
			(start 0.7874 0.4064)
			(end 0.503428 0.4064)
			(stroke
				(width 0.1524)
				(type default)
			)
			(layer "F.SilkS")
		)
		(fp_line
			(start -0.258572 0.4064)
			(end -0.7874 0.4064)
			(stroke
				(width 0.1524)
				(type default)
			)
			(layer "F.SilkS")
		)
		(fp_line
			(start -0.7874 0.4064)
			(end -0.7874 -0.4064)
			(stroke
				(width 0.1524)
				(type default)
			)
			(layer "F.SilkS")
		)
		(fp_line
			(start -0.12065 -0.305054)
			(end -0.12065 -0.2794)
			(stroke
				(width 0.1)
				(type default)
			)
			(layer "F.Fab")
		)
		(fp_line
			(start -0.67945 -0.305054)
			(end -0.12065 -0.305054)
			(stroke
				(width 0.1)
				(type default)
			)
			(layer "F.Fab")
		)
		(fp_line
			(start 0.67945 -0.3048)
			(end 0.67945 0.3048)
			(stroke
				(width 0.1)
				(type default)
			)
			(layer "F.Fab")
		)
		(fp_line
			(start 0.12065 -0.3048)
			(end 0.67945 -0.3048)
			(stroke
				(width 0.1)
				(type default)
			)
			(layer "F.Fab")
		)
		(fp_line
			(start 0.12065 -0.2794)
			(end 0.12065 -0.3048)
			(stroke
				(width 0.1)
				(type default)
			)
			(layer "F.Fab")
		)
		(fp_line
			(start -0.12065 -0.2794)
			(end 0.12065 -0.2794)
			(stroke
				(width 0.1)
				(type default)
			)
			(layer "F.Fab")
		)
		(fp_line
			(start 0.120396 0.2794)
			(end -0.12065 0.2794)
			(stroke
				(width 0.1)
				(type default)
			)
			(layer "F.Fab")
		)
		(fp_line
			(start -0.12065 0.2794)
			(end -0.12065 0.3048)
			(stroke
				(width 0.1)
				(type default)
			)
			(layer "F.Fab")
		)
		(fp_line
			(start 0.67945 0.3048)
			(end 0.120396 0.3048)
			(stroke
				(width 0.1)
				(type default)
			)
			(layer "F.Fab")
		)
		(fp_line
			(start 0.120396 0.3048)
			(end 0.120396 0.2794)
			(stroke
				(width 0.1)
				(type default)
			)
			(layer "F.Fab")
		)
		(fp_line
			(start -0.12065 0.3048)
			(end -0.67945 0.3048)
			(stroke
				(width 0.1)
				(type default)
			)
			(layer "F.Fab")
		)
		(fp_line
			(start -0.67945 0.3048)
			(end -0.67945 -0.305054)
			(stroke
				(width 0.1)
				(type default)
			)
			(layer "F.Fab")
		)
		(pad "1" smd circle
			(at -0.40005 0 90)
			(size 0 0)
			(layers "F.Cu" "F.Mask" "F.Paste")
			(net "PVDDIO_P0_VCC4")
		)
		(pad "2" smd circle
			(at 0.40005 0 90)
			(size 0 0)
			(layers "F.Cu" "F.Mask" "F.Paste")
			(net "GND")
		)
	)
	(footprint ""
		(layer "F.Cu")
		(at 152.040844 -370.57203 -90)
		(property "Reference" "C760"
			(at 0 0 270)
			(layer "F.SilkS")
			(hide yes)
			(effects
				(font
					(size 1.27 1.27)
				)
			)
		)
		(property "Value" ""
			(at 0 0 270)
			(layer "F.Fab")
			(effects
				(font
					(size 1.27 1.27)
				)
			)
		)
		(duplicate_pad_numbers_are_jumpers no)
		(fp_line
			(start -0.299974 0.150114)
			(end -0.299974 -0.150114)
			(stroke
				(width 0.1)
				(type default)
			)
			(layer "F.Fab")
		)
		(fp_line
			(start 0.299974 0.150114)
			(end -0.299974 0.150114)
			(stroke
				(width 0.1)
				(type default)
			)
			(layer "F.Fab")
		)
		(fp_line
			(start -0.299974 -0.150114)
			(end 0.299974 -0.150114)
			(stroke
				(width 0.1)
				(type default)
			)
			(layer "F.Fab")
		)
		(fp_line
			(start 0.299974 -0.150114)
			(end 0.299974 0.150114)
			(stroke
				(width 0.1)
				(type default)
			)
			(layer "F.Fab")
		)
		(pad "1" smd rect
			(at -0.2667 0 270)
			(size 0.3048 0.381)
			(layers "F.Cu" "F.Mask" "F.Paste")
			(net "P5E_CPU1_P2_TX_C_DN<6>")
		)
		(pad "2" smd rect
			(at 0.2667 0 270)
			(size 0.3048 0.381)
			(layers "F.Cu" "F.Mask" "F.Paste")
			(net "P5E_CPU1_P2_TX_DN<6>")
		)
	)
)
